(kicad_pcb
	(version 20221018)
	(generator pcbnew)
	(general
    (thickness 1.518)
  )
	(paper "A4")
	(title_block
    (title "Kria K26 Devboard")
    (date "2024-03-26")
    (rev "1.2.5")
    (comment 1 "www.antmicro.com")
    (comment 2 "Antmicro Ltd.")
		(comment 9 "footprints 26-31 of 660")
	)
	(layers
    (0 "F.Cu" mixed)
    (1 "In1.Cu" power)
    (2 "In2.Cu" mixed)
    (3 "In3.Cu" power)
    (4 "In4.Cu" mixed)
    (5 "In5.Cu" power)
    (6 "In6.Cu" mixed)
    (31 "B.Cu" power)
    (32 "B.Adhes" user "B.Adhesive")
    (33 "F.Adhes" user "F.Adhesive")
    (34 "B.Paste" user)
    (35 "F.Paste" user)
    (36 "B.SilkS" user "B.Silkscreen")
    (37 "F.SilkS" user "F.Silkscreen")
    (38 "B.Mask" user)
    (39 "F.Mask" user)
    (40 "Dwgs.User" user "User.Drawings")
    (41 "Cmts.User" user "User.Comments")
    (42 "Eco1.User" user "User.Eco1")
    (43 "Eco2.User" user "User.Eco2")
    (44 "Edge.Cuts" user)
    (45 "Margin" user)
    (46 "B.CrtYd" user "B.Courtyard")
    (47 "F.CrtYd" user "F.Courtyard")
    (48 "B.Fab" user)
    (49 "F.Fab" user)
  )
	(footprint "kria-k26-devboard-footprints:R_0402_1005Metric" (layer "F.Cu")
    (at 87.3 117.8 180)
    (descr "Resistor SMD 0402")
    (tags "resistor SMD 0402")
    (property "Author" "Antmicro")
    (property "License" "Apache-2.0")
    (property "MPN" "CR0402-FX-4700GLF")
    (property "Manufacturer" "Bourns")
    (property "Sheetfile" "k26_som.kicad_sch")
    (property "Sheetname" "Xilinx K26 SOM")
    (property "Tolerance" "1%")
    (property "Val" "470R")
    (property "ki_description" "470R resistor in 0402 package with 1% tolerance")
    (attr smd)
    (fp_text reference "R80" (at 0.81 5.32 180) (layer "F.SilkS")
        (effects (font (size 0.7 0.7) (thickness 0.15)) (justify left bottom))
    )
    (fp_text value "R_470R_0402" (at 0 1.4 180) (layer "F.Fab") hide
        (effects (font (size 0.7 0.7) (thickness 0.15)) (justify left bottom))
    )
    (fp_text user "License: Apache-2.0" (at -0.95 5.169 180) (layer "F.Fab") hide
        (effects (font (size 0.7 0.7) (thickness 0.15)) (justify left bottom))
    )
    (fp_text user "Author: Antmicro" (at -0.95 4.169 180) (layer "F.Fab") hide
        (effects (font (size 0.7 0.7) (thickness 0.15)) (justify left bottom))
    )
    (fp_text user "${REFERENCE}" (at -0.95 3.168 180) (layer "F.Fab") hide
        (effects (font (size 0.7 0.7) (thickness 0.15)) (justify left bottom))
    )
    (fp_rect (start -0.93 -0.47) (end 0.93 0.47)
      (stroke (width 0.05) (type solid)) (fill none) (layer "F.CrtYd"))
    (fp_rect (start -0.5 -0.25) (end 0.5 0.25)
      (stroke (width 0.15) (type solid)) (fill none) (layer "F.Fab"))
    (pad "1" smd roundrect (at -0.485 0 180) (size 0.59 0.64) (layers "F.Cu" "F.Paste" "F.Mask") (roundrect_rratio 0.25)
      (net 4 "/Xilinx K26 SOM/MODE2_C2M") (pintype "passive"))
    (pad "2" smd roundrect (at 0.485 0 180) (size 0.59 0.64) (layers "F.Cu" "F.Paste" "F.Mask") (roundrect_rratio 0.25)
      (net 1 "GND") (pintype "passive"))
  )
	(footprint "kria-k26-devboard-footprints:R_0402_1005Metric" (layer "F.Cu")
    (at 87.29 118.78 180)
    (descr "Resistor SMD 0402")
    (tags "resistor SMD 0402")
    (property "Author" "Antmicro")
    (property "DNP" "DNP")
    (property "License" "Apache-2.0")
    (property "MPN" "CR0402-FX-4700GLF")
    (property "Manufacturer" "Bourns")
    (property "Sheetfile" "k26_som.kicad_sch")
    (property "Sheetname" "Xilinx K26 SOM")
    (property "Tolerance" "1%")
    (property "Val" "470R")
    (property "dnp" "")
    (property "exclude_from_bom" "")
    (property "ki_description" "470R resistor in 0402 package with 1% tolerance")
    (attr exclude_from_pos_files exclude_from_bom)
    (fp_text reference "R81" (at 0.81 5.32 180) (layer "F.SilkS")
        (effects (font (size 0.7 0.7) (thickness 0.15)) (justify left bottom))
    )
    (fp_text value "R_470R_0402" (at 0 1.4 180) (layer "F.Fab") hide
        (effects (font (size 0.7 0.7) (thickness 0.15)) (justify left bottom))
    )
    (fp_text user "Author: Antmicro" (at -0.95 4.169 180) (layer "F.Fab") hide
        (effects (font (size 0.7 0.7) (thickness 0.15)) (justify left bottom))
    )
    (fp_text user "${REFERENCE}" (at -0.95 3.168 180) (layer "F.Fab") hide
        (effects (font (size 0.7 0.7) (thickness 0.15)) (justify left bottom))
    )
    (fp_text user "License: Apache-2.0" (at -0.95 5.169 180) (layer "F.Fab") hide
        (effects (font (size 0.7 0.7) (thickness 0.15)) (justify left bottom))
    )
    (fp_rect (start -0.93 -0.47) (end 0.93 0.47)
      (stroke (width 0.05) (type solid)) (fill none) (layer "F.CrtYd"))
    (fp_rect (start -0.5 -0.25) (end 0.5 0.25)
      (stroke (width 0.15) (type solid)) (fill none) (layer "F.Fab"))
    (pad "1" smd roundrect (at -0.485 0 180) (size 0.59 0.64) (layers "F.Cu" "F.Paste" "F.Mask") (roundrect_rratio 0.25)
      (net 3 "/Xilinx K26 SOM/MODE1_C2M") (pintype "passive"))
    (pad "2" smd roundrect (at 0.485 0 180) (size 0.59 0.64) (layers "F.Cu" "F.Paste" "F.Mask") (roundrect_rratio 0.25)
      (net 1 "GND") (pintype "passive"))
  )
	(footprint "kria-k26-devboard-footprints:R_0402_1005Metric" (layer "F.Cu")
    (at 87.29 119.77 180)
    (descr "Resistor SMD 0402")
    (tags "resistor SMD 0402")
    (property "Author" "Antmicro")
    (property "License" "Apache-2.0")
    (property "MPN" "CR0402-FX-4700GLF")
    (property "Manufacturer" "Bourns")
    (property "Sheetfile" "k26_som.kicad_sch")
    (property "Sheetname" "Xilinx K26 SOM")
    (property "Tolerance" "1%")
    (property "Val" "470R")
    (property "ki_description" "470R resistor in 0402 package with 1% tolerance")
    (attr smd)
    (fp_text reference "R82" (at 0.81 5.32 180) (layer "F.SilkS")
        (effects (font (size 0.7 0.7) (thickness 0.15)) (justify left bottom))
    )
    (fp_text value "R_470R_0402" (at 0 1.4 180) (layer "F.Fab") hide
        (effects (font (size 0.7 0.7) (thickness 0.15)) (justify left bottom))
    )
    (fp_text user "Author: Antmicro" (at -0.95 4.169 180) (layer "F.Fab") hide
        (effects (font (size 0.7 0.7) (thickness 0.15)) (justify left bottom))
    )
    (fp_text user "${REFERENCE}" (at -0.95 3.168 180) (layer "F.Fab") hide
        (effects (font (size 0.7 0.7) (thickness 0.15)) (justify left bottom))
    )
    (fp_text user "License: Apache-2.0" (at -0.95 5.169 180) (layer "F.Fab") hide
        (effects (font (size 0.7 0.7) (thickness 0.15)) (justify left bottom))
    )
    (fp_rect (start -0.93 -0.47) (end 0.93 0.47)
      (stroke (width 0.05) (type solid)) (fill none) (layer "F.CrtYd"))
    (fp_rect (start -0.5 -0.25) (end 0.5 0.25)
      (stroke (width 0.15) (type solid)) (fill none) (layer "F.Fab"))
    (pad "1" smd roundrect (at -0.485 0 180) (size 0.59 0.64) (layers "F.Cu" "F.Paste" "F.Mask") (roundrect_rratio 0.25)
      (net 2 "/Xilinx K26 SOM/MODE0_C2M") (pintype "passive"))
    (pad "2" smd roundrect (at 0.485 0 180) (size 0.59 0.64) (layers "F.Cu" "F.Paste" "F.Mask") (roundrect_rratio 0.25)
      (net 1 "GND") (pintype "passive"))
  )
	(footprint "kria-k26-devboard-footprints:Spacer_Drill4.45mm_H5mm_9774050960R" (layer "F.Cu")
    (at 160.206999 90.7935)
    (property "Author" "Antmicro")
    (property "License" "Apache-2.0")
    (property "MPN" "9774050960R")
    (property "Manufacturer" "Würth Elektronik")
    (property "Sheetfile" "k26_som.kicad_sch")
    (property "Sheetname" "Xilinx K26 SOM")
    (property "ki_description" "Spacer, SMT, Non Stop, Steel, Swage Round, 6 mm x 5 mm, 3.3 mm Internal, WA-SMST Series")
    (property "ki_keywords" "SPACER")
    (clearance 0.6)
    (attr smd)
    (fp_text reference "SP3" (at 0 -3.4) (layer "F.SilkS")
        (effects (font (size 0.7 0.7) (thickness 0.15)) (justify left bottom))
    )
    (fp_text value "Spacer_Drill4.45mm_H5mm_9774050960R" (at 0 4.2) (layer "F.Fab")
        (effects (font (size 0.7 0.7) (thickness 0.15)) (justify left bottom))
    )
    (fp_text user "${REFERENCE}" (at -3.25 7.4) (layer "F.Fab") hide
        (effects (font (size 0.7 0.7) (thickness 0.15)) (justify left bottom))
    )
    (fp_text user "Author: Antmicro" (at -3.25 8.6) (layer "F.Fab") hide
        (effects (font (size 0.7 0.7) (thickness 0.15)) (justify left bottom))
    )
    (fp_text user "License: Apache-2.0" (at -3.25 6.2) (layer "F.Fab") hide
        (effects (font (size 0.7 0.7) (thickness 0.15)) (justify left bottom))
    )
    (fp_circle (center 0 0) (end 3.25 0)
      (stroke (width 0.05) (type solid)) (fill none) (layer "F.CrtYd"))
    (fp_circle (center 0 0) (end 2.564 0)
      (stroke (width 0.15) (type solid)) (fill none) (layer "F.Fab"))
    (pad "1" thru_hole circle (at 0 0) (size 6 6) (drill 4.45) (layers "*.Cu" "*.Mask" "F.Paste")
      (net 1 "GND") (pintype "passive") (solder_paste_margin_ratio -0.05))
  )
	(footprint "kria-k26-devboard-footprints:SOT1161-2" (layer "F.Cu")
    (at 129.925 136.975 -90)
    (descr "SOT1161-2")
    (tags "Integrated Circuit")
    (property "Author" "Antmicro")
    (property "License" "Apache-2.0")
    (property "MPN" "NVT4858HKZ")
    (property "Manufacturer" "NXP")
    (property "Sheetfile" "sd-3-card.kicad_sch")
    (property "Sheetname" "SD 3.0 card")
    (property "ki_description" "Level Translator, 4 Input, 1.08 V to 1.98 V, xQFN-16")
    (property "ki_keywords" "SMT, LEVEL-SHIFTER, IC, LOGIC")
    (attr smd)
    (fp_text reference "U5" (at -1.415 1.175) (layer "F.SilkS")
        (effects (font (size 0.7 0.7) (thickness 0.15)) (justify left bottom))
    )
    (fp_text value "NVT4858_XQFN" (at 0 2.7 -90) (layer "F.Fab") hide
        (effects (font (size 0.7 0.7) (thickness 0.15)) (justify left bottom))
    )
    (fp_text user "Author: Antmicro" (at -1.5 4.498 -90) (layer "F.Fab") hide
        (effects (font (size 0.7 0.7) (thickness 0.15)) (justify left bottom))
    )
    (fp_text user "License: Apache-2.0" (at -1.5 5.7 -90) (layer "F.Fab") hide
        (effects (font (size 0.7 0.7) (thickness 0.15)) (justify left bottom))
    )
    (fp_line (start -0.902 0.9) (end -0.902 1.3)
      (stroke (width 0.15) (type solid)) (layer "F.SilkS"))
    (fp_line (start -0.9 -0.9) (end -0.9 -1.3)
      (stroke (width 0.15) (type solid)) (layer "F.SilkS"))
    (fp_line (start 0.9 -0.901) (end 0.9 -1.301)
      (stroke (width 0.15) (type solid)) (layer "F.SilkS"))
    (fp_line (start 0.9 0.9) (end 0.9 1.3)
      (stroke (width 0.15) (type solid)) (layer "F.SilkS"))
    (fp_circle (center -1.6 -1.7) (end -1.55 -1.7)
      (stroke (width 0.15) (type solid)) (fill solid) (layer "F.SilkS"))
    (fp_rect (start -1.3 -1.7) (end 1.3 1.7)
      (stroke (width 0.05) (type solid)) (fill none) (layer "F.CrtYd"))
    (fp_line (start -0.902 -1.301) (end 0.9 -1.301)
      (stroke (width 0.15) (type solid)) (layer "F.Fab"))
    (fp_line (start -0.902 1.3) (end -0.902 -1.301)
      (stroke (width 0.15) (type solid)) (layer "F.Fab"))
    (fp_line (start 0.9 -1.301) (end 0.9 1.3)
      (stroke (width 0.15) (type solid)) (layer "F.Fab"))
    (fp_line (start 0.9 1.3) (end -0.902 1.3)
      (stroke (width 0.15) (type solid)) (layer "F.Fab"))
    (pad "1" smd roundrect (at -0.6 -0.6) (size 0.22 0.9) (layers "F.Cu" "F.Paste" "F.Mask") (roundrect_rratio 0.25)
      (net 640 "Net-(R15-R2.2)") (pinfunction "DAT2_{A}") (pintype "bidirectional"))
    (pad "2" smd roundrect (at -0.625 -0.202) (size 0.22 0.9) (layers "F.Cu" "F.Paste" "F.Mask") (roundrect_rratio 0.25)
      (net 641 "Net-(R15-R1.2)") (pinfunction "DAT3_{A}") (pintype "bidirectional"))
    (pad "3" smd roundrect (at -0.625 0.2) (size 0.22 0.9) (layers "F.Cu" "F.Paste" "F.Mask") (roundrect_rratio 0.25)
      (net 638 "Net-(R15-R4.2)") (pinfunction "DAT0_{A}") (pintype "bidirectional"))
    (pad "4" smd roundrect (at -0.625 0.598) (size 0.22 0.9) (layers "F.Cu" "F.Paste" "F.Mask") (roundrect_rratio 0.25)
      (net 639 "Net-(R15-R3.2)") (pinfunction "DAT1_{A}") (pintype "bidirectional"))
    (pad "5" smd roundrect (at -0.6 1.175 270) (size 0.22 0.55) (layers "F.Cu" "F.Paste" "F.Mask") (roundrect_rratio 0.25)
      (net 436 "Net-(U5-CLK_{A})") (pinfunction "CLK_{A}") (pintype "input"))
    (pad "6" smd roundrect (at -0.202 1.175 270) (size 0.22 0.55) (layers "F.Cu" "F.Paste" "F.Mask") (roundrect_rratio 0.25)
      (net 705 "unconnected-(U5-CLK_{FB}-Pad6)") (pinfunction "CLK_{FB}") (pintype "output+no_connect"))
    (pad "7" smd roundrect (at 0.2 1.175 270) (size 0.22 0.55) (layers "F.Cu" "F.Paste" "F.Mask") (roundrect_rratio 0.25)
      (net 1 "GND") (pinfunction "GND") (pintype "power_in"))
    (pad "8" smd roundrect (at 0.598 1.175 270) (size 0.22 0.55) (layers "F.Cu" "F.Paste" "F.Mask") (roundrect_rratio 0.25)
      (net 261 "/SD 3.0 card/SD_CLK") (pinfunction "CLK_{B}") (pintype "output"))
    (pad "9" smd roundrect (at 0.623 0.598) (size 0.22 0.9) (layers "F.Cu" "F.Paste" "F.Mask") (roundrect_rratio 0.25)
      (net 259 "/SD 3.0 card/SD_DAT1") (pinfunction "DAT1_{B}") (pintype "bidirectional"))
    (pad "10" smd roundrect (at 0.623 0.2) (size 0.22 0.9) (layers "F.Cu" "F.Paste" "F.Mask") (roundrect_rratio 0.25)
      (net 260 "/SD 3.0 card/SD_DAT0") (pinfunction "DAT0_{B}") (pintype "bidirectional"))
    (pad "11" smd roundrect (at 0.623 -0.202) (size 0.22 0.9) (layers "F.Cu" "F.Paste" "F.Mask") (roundrect_rratio 0.25)
      (net 263 "/SD 3.0 card/SD_DAT3") (pinfunction "DAT3_{B}") (pintype "bidirectional"))
    (pad "12" smd roundrect (at 0.623 -0.6) (size 0.22 0.9) (layers "F.Cu" "F.Paste" "F.Mask") (roundrect_rratio 0.25)
      (net 264 "/SD 3.0 card/SD_DAT2") (pinfunction "DAT2_{B}") (pintype "bidirectional"))
    (pad "13" smd roundrect (at 0.598 -1.176 270) (size 0.22 0.55) (layers "F.Cu" "F.Paste" "F.Mask") (roundrect_rratio 0.25)
      (net 262 "/SD 3.0 card/SD_CMD") (pinfunction "CMD_{B}") (pintype "bidirectional"))
    (pad "14" smd roundrect (at 0.2 -1.176 270) (size 0.22 0.55) (layers "F.Cu" "F.Paste" "F.Mask") (roundrect_rratio 0.25)
      (net 104 "/SD 3.0 card/VCCB") (pinfunction "VCC_{B}") (pintype "power_in"))
    (pad "15" smd roundrect (at -0.202 -1.176 270) (size 0.22 0.55) (layers "F.Cu" "F.Paste" "F.Mask") (roundrect_rratio 0.25)
      (net 17 "PS_1V8") (pinfunction "VCC_{A}") (pintype "power_in"))
    (pad "16" smd roundrect (at -0.6 -1.176 270) (size 0.22 0.55) (layers "F.Cu" "F.Paste" "F.Mask") (roundrect_rratio 0.25)
      (net 435 "Net-(U5-CMD_{A})") (pinfunction "CMD_{A}") (pintype "bidirectional"))
  )
	(footprint "kria-k26-devboard-footprints:SOIC-8_3.9x4.9x1.75mm_P1.27mm" (layer "F.Cu")
    (at 110.2 101.675 -90)
    (tags "Integrated Circuit")
    (property "Author" "Antmicro")
    (property "License" "Apache-2.0")
    (property "MPN" "SN65LVDS1DR")
    (property "Manufacturer" "Texas Instruments")
    (property "Sheetfile" "clock.kicad_sch")
    (property "Sheetname" "Clock distribution")
    (property "ki_description" "LVDS Interface IC Single LVDS Transmitter")
    (property "ki_keywords" "SMT, INTERFACE, IC, LVDS")
    (attr smd)
    (fp_text reference "U8" (at 0.635 -3.58 -90) (layer "F.SilkS")
        (effects (font (size 0.7 0.7) (thickness 0.15)) (justify left bottom))
    )
    (fp_text value "SN65LVDS1_SOIC" (at 0 3.65 -90) (layer "F.Fab")
        (effects (font (size 0.7 0.7) (thickness 0.15)) (justify left bottom))
    )
    (fp_text user "License: Apache-2.0" (at -3.476 5.099 -90) (layer "F.Fab") hide
        (effects (font (size 0.7 0.7) (thickness 0.15)) (justify left bottom))
    )
    (fp_text user "Author: Antmicro" (at -3.476 6.099 -90) (layer "F.Fab") hide
        (effects (font (size 0.7 0.7) (thickness 0.15)) (justify left bottom))
    )
    (fp_text user "${REFERENCE}" (at -3.476 7.099 -90) (layer "F.Fab") hide
        (effects (font (size 0.7 0.7) (thickness 0.15)) (justify left bottom))
    )
    (fp_line (start -1.95 -2.452) (end 1.95 -2.45)
      (stroke (width 0.15) (type solid)) (layer "F.SilkS"))
    (fp_line (start -1.95 2.45) (end 1.95 2.45)
      (stroke (width 0.15) (type solid)) (layer "F.SilkS"))
    (fp_circle (center -2.4 -2.45) (end -2.35 -2.4)
      (stroke (width 0.15) (type solid)) (fill solid) (layer "F.SilkS"))
    (fp_rect (start -3.625 -2.7) (end 3.625 2.7)
      (stroke (width 0.05) (type solid)) (fill none) (layer "F.CrtYd"))
    (fp_line (start -1.95 -1.18) (end -0.683 -2.452)
      (stroke (width 0.15) (type solid)) (layer "F.Fab"))
    (fp_line (start -1.95 2.45) (end -1.95 -1.18)
      (stroke (width 0.15) (type solid)) (layer "F.Fab"))
    (fp_line (start -0.683 -2.452) (end 1.949 -2.452)
      (stroke (width 0.15) (type solid)) (layer "F.Fab"))
    (fp_line (start 1.949 -2.452) (end 1.949 2.45)
      (stroke (width 0.15) (type solid)) (layer "F.Fab"))
    (fp_line (start 1.949 2.45) (end -1.95 2.45)
      (stroke (width 0.15) (type solid)) (layer "F.Fab"))
    (pad "1" smd roundrect (at -2.714 -1.905) (size 0.65 1.525) (layers "F.Cu" "F.Paste" "F.Mask") (roundrect_rratio 0.25)
      (net 15 "PS_3V3") (pinfunction "VDD") (pintype "power_in"))
    (pad "2" smd roundrect (at -2.714 -0.635) (size 0.65 1.525) (layers "F.Cu" "F.Paste" "F.Mask") (roundrect_rratio 0.25)
      (net 698 "Net-(U8-IN)") (pinfunction "IN") (pintype "input"))
    (pad "3" smd roundrect (at -2.714 0.632) (size 0.65 1.525) (layers "F.Cu" "F.Paste" "F.Mask") (roundrect_rratio 0.25)
      (net 706 "unconnected-(U8-NC-Pad3)") (pinfunction "NC") (pintype "no_connect"))
    (pad "4" smd roundrect (at -2.714 1.902) (size 0.65 1.525) (layers "F.Cu" "F.Paste" "F.Mask") (roundrect_rratio 0.25)
      (net 1 "GND") (pinfunction "GND") (pintype "power_in"))
    (pad "5" smd roundrect (at 2.712 1.902) (size 0.65 1.525) (layers "F.Cu" "F.Paste" "F.Mask") (roundrect_rratio 0.25)
      (net 707 "unconnected-(U8-NC-Pad5)") (pinfunction "NC") (pintype "no_connect"))
    (pad "6" smd roundrect (at 2.712 0.632) (size 0.65 1.525) (layers "F.Cu" "F.Paste" "F.Mask") (roundrect_rratio 0.25)
      (net 708 "unconnected-(U8-NC-Pad6)") (pinfunction "NC") (pintype "no_connect"))
    (pad "7" smd roundrect (at 2.712 -0.635) (size 0.65 1.525) (layers "F.Cu" "F.Paste" "F.Mask") (roundrect_rratio 0.25)
      (net 179 "/Clock distribution/GTR_REFCLK1_C2M_P") (pinfunction "OUT+") (pintype "output"))
    (pad "8" smd roundrect (at 2.712 -1.905) (size 0.65 1.525) (layers "F.Cu" "F.Paste" "F.Mask") (roundrect_rratio 0.25)
      (net 180 "/Clock distribution/GTR_REFCLK1_C2M_N") (pinfunction "OUT-") (pintype "output"))
  )
)
